# BASEBOARD_FAB2 (Tioga Pass) — schematic netlist excerpt (pin names and nets, part order shuffled) for the footprints in the layout excerpt that follows; sources: Cadence DE-HDL packaged netlist, KiCad conversion of Wiwynn_Tioga_Pass_MB.brd

C5P38  CAP  100UF 4V 20% X5R  pkg 0805  page 217 : A = PVDDQ_ABC ; B = GND
C2T35  CAP_A  0.1UF 16V 10% X7R  pkg 0402V  page 156 : A = P3V3_STBY ; B = GND
C2L19  CAP_A  0.01UF 25V 10% X7R  pkg 0402V  page 173 : A = SATA6G_PCH_PCIE_UP_SATA_RXP<0> ; B = SATA6G_P0_RX_C_DP

(kicad_pcb
	(version 20260206)
	(generator "pcbnew")
	(generator_version "10.0")
	(general
		(thickness 1.6)
		(legacy_teardrops no)
	)
	(paper "A4")
	(title_block
		(title "Wiwynn_Tioga_Pass_MB.brd")
		(comment 1 "Tioga Pass / footprints 4061-4063 of 4770")
	)
	(layers
		(0 "F.Cu" signal "TOP")
		(4 "In1.Cu" signal "L2GND")
		(6 "In2.Cu" signal "L3")
		(8 "In3.Cu" signal "L4GND")
		(10 "In4.Cu" signal "L5")
		(12 "In5.Cu" signal "L6GND")
		(14 "In6.Cu" signal "L7VCC")
		(16 "In7.Cu" signal "L8VCC")
		(18 "In8.Cu" signal "L9GND")
		(20 "In9.Cu" signal "L10")
		(22 "In10.Cu" signal "L11GND")
		(24 "In11.Cu" signal "L12")
		(26 "In12.Cu" signal "L13GND")
		(2 "B.Cu" signal "BOTTOM")
		(9 "F.Adhes" user "F.Adhesive")
		(11 "B.Adhes" user "B.Adhesive")
		(13 "F.Paste" user "Package Geometry/Pastemask Top")
		(15 "B.Paste" user "Package Geometry/Pastemask Bottom")
		(5 "F.SilkS" user "Ref Des/Silkscreen Top")
		(7 "B.SilkS" user "Ref Des/Silkscreen Bottom")
		(1 "F.Mask" user "Board Geometry/Soldermask Top")
		(3 "B.Mask" user "Board Geometry/Soldermask Bottom")
		(17 "Dwgs.User" user "User.Drawings")
		(19 "Cmts.User" user "User.Comments")
		(21 "Eco1.User" user "User.Eco1")
		(23 "Eco2.User" user "User.Eco2")
		(25 "Edge.Cuts" user "Board Geometry/Outline")
		(27 "Margin" user)
		(31 "F.CrtYd" user "Package Geometry/Place Bound Top")
		(29 "B.CrtYd" user "Package Geometry/Place Bound Bottom")
		(35 "F.Fab" user "Ref Des/Assembly Top")
		(33 "B.Fab" user "Ref Des/Assembly Bottom")
	)
	(footprint ""
		(layer "B.Cu")
		(at 264.428224 -69.098414 -90)
		(property "Reference" "C5P38"
			(at 0 0 90)
			(layer "B.SilkS")
			(hide yes)
			(effects
				(font
					(size 1.27 1.27)
				)
				(justify mirror)
			)
		)
		(property "Value" ""
			(at 0 0 90)
			(layer "B.Fab")
			(effects
				(font
					(size 1.27 1.27)
				)
				(justify mirror)
			)
		)
		(duplicate_pad_numbers_are_jumpers no)
		(fp_poly
			(pts
				(xy 0.7239 -0.2159) (xy -0.7239 -0.2159) (xy -0.7239 1.9939) (xy 0.7239 1.9939)
			)
			(stroke
				(width 0)
				(type default)
			)
			(fill no)
			(layer "B.CrtYd")
		)
		(fp_line
			(start -0.7239 1.9939)
			(end -0.7239 -0.2159)
			(stroke
				(width 0.1)
				(type default)
			)
			(layer "B.Fab")
		)
		(fp_line
			(start 0.7239 1.9939)
			(end -0.7239 1.9939)
			(stroke
				(width 0.1)
				(type default)
			)
			(layer "B.Fab")
		)
		(fp_line
			(start -0.7239 -0.2159)
			(end 0.7239 -0.2159)
			(stroke
				(width 0.1)
				(type default)
			)
			(layer "B.Fab")
		)
		(fp_line
			(start 0.7239 -0.2159)
			(end 0.7239 1.9939)
			(stroke
				(width 0.1)
				(type default)
			)
			(layer "B.Fab")
		)
		(pad "1" smd rect
			(at 0 0 90)
			(size 1.27 1.016)
			(layers "B.Cu" "B.Mask" "B.Paste")
			(net "PVDDQ_ABC")
		)
		(pad "2" smd rect
			(at 0 1.778 90)
			(size 1.27 1.016)
			(layers "B.Cu" "B.Mask" "B.Paste")
			(net "GND")
		)
		(zone
			(layer "B.Cu")
			(hatch none 0.5)
			(connect_pads
				(clearance 0)
			)
			(min_thickness 0.25)
			(keepout
				(tracks not_allowed)
				(vias allowed)
				(pads allowed)
				(copperpour not_allowed)
				(footprints allowed)
			)
			(placement
				(enabled no)
				(sheetname "")
			)
			(fill
				(thermal_gap 0.5)
				(thermal_bridge_width 0.5)
				(island_removal_mode 0)
			)
			(polygon
				(pts
					(xy 263.920224 -68.463414) (xy 263.920224 -69.733414) (xy 263.158224 -69.733414) (xy 263.158224 -68.463414)
				)
			)
		)
	)
	(footprint ""
		(layer "B.Cu")
		(at 422.70172 -149.098 90)
		(property "Reference" "C2L19"
			(at 0 0 90)
			(layer "B.SilkS")
			(hide yes)
			(effects
				(font
					(size 1.27 1.27)
				)
				(justify mirror)
			)
		)
		(property "Value" ""
			(at 0 0 90)
			(layer "B.Fab")
			(effects
				(font
					(size 1.27 1.27)
				)
				(justify mirror)
			)
		)
		(duplicate_pad_numbers_are_jumpers no)
		(fp_poly
			(pts
				(xy -0.3048 -0.1016) (xy -0.3048 0.9906) (xy 0.3048 0.9906) (xy 0.3048 -0.1016)
			)
			(stroke
				(width 0)
				(type default)
			)
			(fill no)
			(layer "B.CrtYd")
		)
		(fp_line
			(start 0.3048 -0.1016)
			(end 0.3048 0.9906)
			(stroke
				(width 0.1)
				(type default)
			)
			(layer "B.Fab")
		)
		(fp_line
			(start -0.3048 -0.1016)
			(end 0.3048 -0.1016)
			(stroke
				(width 0.1)
				(type default)
			)
			(layer "B.Fab")
		)
		(fp_line
			(start 0.3048 0.9906)
			(end -0.3048 0.9906)
			(stroke
				(width 0.1)
				(type default)
			)
			(layer "B.Fab")
		)
		(fp_line
			(start -0.3048 0.9906)
			(end -0.3048 -0.1016)
			(stroke
				(width 0.1)
				(type default)
			)
			(layer "B.Fab")
		)
		(pad "1" smd rect
			(at 0 0 270)
			(size 0.508 0.508)
			(layers "B.Cu" "B.Mask" "B.Paste")
			(net "SATA6G_PCH_PCIE_UP_SATA_RXP<0>")
		)
		(pad "2" smd rect
			(at 0 0.889 270)
			(size 0.508 0.508)
			(layers "B.Cu" "B.Mask" "B.Paste")
			(net "SATA6G_P0_RX_C_DP")
		)
		(zone
			(layer "B.Cu")
			(hatch none 0.5)
			(connect_pads
				(clearance 0)
			)
			(min_thickness 0.25)
			(keepout
				(tracks allowed)
				(vias not_allowed)
				(pads allowed)
				(copperpour not_allowed)
				(footprints allowed)
			)
			(placement
				(enabled no)
				(sheetname "")
			)
			(fill
				(thermal_gap 0.5)
				(thermal_bridge_width 0.5)
				(island_removal_mode 0)
			)
			(polygon
				(pts
					(xy 422.95572 -149.352) (xy 422.95572 -148.844) (xy 423.33672 -148.844) (xy 423.33672 -149.352)
				)
			)
		)
		(zone
			(layer "B.Cu")
			(hatch none 0.5)
			(connect_pads
				(clearance 0)
			)
			(min_thickness 0.25)
			(keepout
				(tracks not_allowed)
				(vias allowed)
				(pads allowed)
				(copperpour not_allowed)
				(footprints allowed)
			)
			(placement
				(enabled no)
				(sheetname "")
			)
			(fill
				(thermal_gap 0.5)
				(thermal_bridge_width 0.5)
				(island_removal_mode 0)
			)
			(polygon
				(pts
					(xy 423.33672 -149.352) (xy 423.33672 -148.844) (xy 422.95572 -148.844) (xy 422.95572 -149.352)
				)
			)
		)
	)
	(footprint ""
		(layer "B.Cu")
		(at 393.446 -28.575 -90)
		(property "Reference" "C2T35"
			(at 0 0 90)
			(layer "B.SilkS")
			(hide yes)
			(effects
				(font
					(size 1.27 1.27)
				)
				(justify mirror)
			)
		)
		(property "Value" ""
			(at 0 0 90)
			(layer "B.Fab")
			(effects
				(font
					(size 1.27 1.27)
				)
				(justify mirror)
			)
		)
		(duplicate_pad_numbers_are_jumpers no)
		(fp_poly
			(pts
				(xy -0.3048 -0.1016) (xy -0.3048 0.9906) (xy 0.3048 0.9906) (xy 0.3048 -0.1016)
			)
			(stroke
				(width 0)
				(type default)
			)
			(fill no)
			(layer "B.CrtYd")
		)
		(fp_line
			(start -0.3048 0.9906)
			(end -0.3048 -0.1016)
			(stroke
				(width 0.1)
				(type default)
			)
			(layer "B.Fab")
		)
		(fp_line
			(start 0.3048 0.9906)
			(end -0.3048 0.9906)
			(stroke
				(width 0.1)
				(type default)
			)
			(layer "B.Fab")
		)
		(fp_line
			(start -0.3048 -0.1016)
			(end 0.3048 -0.1016)
			(stroke
				(width 0.1)
				(type default)
			)
			(layer "B.Fab")
		)
		(fp_line
			(start 0.3048 -0.1016)
			(end 0.3048 0.9906)
			(stroke
				(width 0.1)
				(type default)
			)
			(layer "B.Fab")
		)
		(pad "1" smd rect
			(at 0 0 90)
			(size 0.508 0.508)
			(layers "B.Cu" "B.Mask" "B.Paste")
			(net "P3V3_STBY")
		)
		(pad "2" smd rect
			(at 0 0.889 90)
			(size 0.508 0.508)
			(layers "B.Cu" "B.Mask" "B.Paste")
			(net "GND")
		)
	)
)
